FILE_TYPE = MULTI_PHYS_TABLE;

PART 'NCP45560IMNTWG_H_DFN12'
CLASS=IC

{========================================================================================}
:CLS_PN       = JEDEC_TYPE | ALT_SYMBOLS | DESCRIPTION                 ;
{========================================================================================}
 'G222-10203-01'(!) = 'DFN13_118_P0197_TR071X096'   | '(DFN13_118_P0197_TR071X096_AWS,DFN13_118_P0197_TR071X096_VIA)'  | 'IC,NCP45560-H,ECOSWITCH,0.5-13.5VIN,DFN12'

END_PART

END.
